(kicad_pcb
	(version 20260206)
	(generator "pcbnew")
	(generator_version "10.0")
	(general
		(thickness 1.6)
		(legacy_teardrops no)
	)
	(paper "A4")
	(title_block
		(title "fcb — 12433-1M.1206WZS1330.brd")
		(comment 1 "Open Vault / Knox (Wiwynn) / footprints 193-200 of 495")
	)
	(layers
		(0 "F.Cu" signal "TOP")
		(4 "In1.Cu" signal "L2GND")
		(6 "In2.Cu" signal "L3VCC")
		(2 "B.Cu" signal "BOTTOM")
		(9 "F.Adhes" user "F.Adhesive")
		(11 "B.Adhes" user "B.Adhesive")
		(13 "F.Paste" user "Package Geometry/Pastemask Top")
		(15 "B.Paste" user "Package Geometry/Pastemask Bottom")
		(5 "F.SilkS" user "Ref Des/Silkscreen Top")
		(7 "B.SilkS" user "Ref Des/Silkscreen Bottom")
		(1 "F.Mask" user "Board Geometry/Soldermask Top")
		(3 "B.Mask" user "Board Geometry/Soldermask Bottom")
		(17 "Dwgs.User" user "User.Drawings")
		(19 "Cmts.User" user "User.Comments")
		(21 "Eco1.User" user "User.Eco1")
		(23 "Eco2.User" user "User.Eco2")
		(25 "Edge.Cuts" user "Board Geometry/Outline")
		(27 "Margin" user)
		(31 "F.CrtYd" user "Package Geometry/Place Bound Top")
		(29 "B.CrtYd" user "Package Geometry/Place Bound Bottom")
		(35 "F.Fab" user "Ref Des/Assembly Top")
		(33 "B.Fab" user "Ref Des/Assembly Bottom")
	)
	(footprint ""
		(layer "F.Cu")
		(at 37.2618 -121.793)
		(property "Reference" "C257"
			(at 0 0 0)
			(layer "F.SilkS")
			(hide yes)
			(effects
				(font
					(size 1.27 1.27)
				)
			)
		)
		(property "Value" "SC1U25V3KX-1-GP"
			(at 0 -2.8194 0)
			(unlocked yes)
			(layer "F.Fab")
			(hide yes)
			(effects
				(font
					(size 1.016 1.016)
					(thickness 0.1524)
				)
			)
		)
		(property "Device Type" "C603H36"
			(at 0 -4.3434 0)
			(unlocked yes)
			(layer "F.Fab")
			(hide yes)
			(effects
				(font
					(size 1.016 1.016)
					(thickness 0.1524)
				)
			)
		)
		(duplicate_pad_numbers_are_jumpers no)
		(fp_line
			(start 0.508 0)
			(end -0.508 0)
			(stroke
				(width 0.2032)
				(type default)
			)
			(layer "F.SilkS")
		)
		(fp_rect
			(start -0.5842 1.3335)
			(end 0.5842 -1.3335)
			(stroke
				(width 0)
				(type default)
			)
			(fill no)
			(layer "F.CrtYd")
		)
		(fp_rect
			(start -0.5842 1.3335)
			(end 0.5842 -1.3335)
			(stroke
				(width 0)
				(type default)
			)
			(fill no)
			(layer "F.Fab")
		)
		(pad "1" smd custom
			(at 0 -0.762)
			(size 0.2159 0.2159)
			(layers "F.Cu" "F.Mask" "F.Paste")
			(net "P12V")
			(options
				(clearance outline)
				(anchor circle)
			)
			(primitives
				(gr_poly
					(pts
						(arc
							(start -0.3302 -0.4318)
							(mid -0.402042 -0.402042)
							(end -0.4318 -0.3302)
						)
						(arc
							(start -0.4318 0.3302)
							(mid -0.402042 0.402042)
							(end -0.3302 0.4318)
						)
						(arc
							(start 0.3302 0.4318)
							(mid 0.402042 0.402042)
							(end 0.4318 0.3302)
						)
						(arc
							(start 0.4318 -0.3302)
							(mid 0.402042 -0.402042)
							(end 0.3302 -0.4318)
						)
					)
					(width 0)
					(fill yes)
				)
			)
		)
		(pad "2" smd custom
			(at 0 0.762)
			(size 0.2159 0.2159)
			(layers "F.Cu" "F.Mask" "F.Paste")
			(net "GND")
			(options
				(clearance outline)
				(anchor circle)
			)
			(primitives
				(gr_poly
					(pts
						(arc
							(start -0.3302 -0.4318)
							(mid -0.402042 -0.402042)
							(end -0.4318 -0.3302)
						)
						(arc
							(start -0.4318 0.3302)
							(mid -0.402042 0.402042)
							(end -0.3302 0.4318)
						)
						(arc
							(start 0.3302 0.4318)
							(mid 0.402042 0.402042)
							(end 0.4318 0.3302)
						)
						(arc
							(start 0.4318 -0.3302)
							(mid 0.402042 -0.402042)
							(end 0.3302 -0.4318)
						)
					)
					(width 0)
					(fill yes)
				)
			)
		)
	)
	(footprint ""
		(layer "F.Cu")
		(at 14.8844 -44.5262 90)
		(property "Reference" "R171"
			(at 0 0 90)
			(layer "F.SilkS")
			(hide yes)
			(effects
				(font
					(size 1.27 1.27)
				)
			)
		)
		(property "Value" "0R2J-2-GP"
			(at 0.064008 -3.993896 90)
			(unlocked yes)
			(layer "F.Fab")
			(hide yes)
			(effects
				(font
					(size 1.016 1.016)
					(thickness 0.1524)
				)
			)
		)
		(property "Device Type" "R402H16"
			(at 0.064008 -5.517896 90)
			(unlocked yes)
			(layer "F.Fab")
			(hide yes)
			(effects
				(font
					(size 1.016 1.016)
					(thickness 0.1524)
				)
			)
		)
		(duplicate_pad_numbers_are_jumpers no)
		(fp_line
			(start 0.508 -0.9398)
			(end -0.508 -0.9398)
			(stroke
				(width 0.1524)
				(type default)
			)
			(layer "F.SilkS")
		)
		(fp_line
			(start -0.508 -0.9398)
			(end -0.508 0.9398)
			(stroke
				(width 0.1524)
				(type default)
			)
			(layer "F.SilkS")
		)
		(fp_rect
			(start -0.508 0.9398)
			(end 0.508 -0.9398)
			(stroke
				(width 0)
				(type default)
			)
			(fill no)
			(layer "F.CrtYd")
		)
		(fp_rect
			(start -0.508 0.9398)
			(end 0.508 -0.9398)
			(stroke
				(width 0)
				(type default)
			)
			(fill no)
			(layer "F.Fab")
		)
		(pad "1" smd custom
			(at 0 -0.4445 90)
			(size 0.1397 0.1397)
			(layers "F.Cu" "F.Mask" "F.Paste")
			(net "SELF_1A_HB")
			(options
				(clearance outline)
				(anchor circle)
			)
			(primitives
				(gr_poly
					(pts
						(arc
							(start -0.1778 -0.2794)
							(mid -0.249642 -0.249642)
							(end -0.2794 -0.1778)
						)
						(arc
							(start -0.2794 0.1778)
							(mid -0.249642 0.249642)
							(end -0.1778 0.2794)
						)
						(arc
							(start 0.1778 0.2794)
							(mid 0.249642 0.249642)
							(end 0.2794 0.1778)
						)
						(arc
							(start 0.2794 -0.1778)
							(mid 0.249642 -0.249642)
							(end 0.1778 -0.2794)
						)
					)
					(width 0)
					(fill yes)
				)
			)
		)
		(pad "2" smd custom
			(at 0 0.4445 90)
			(size 0.1397 0.1397)
			(layers "F.Cu" "F.Mask" "F.Paste")
			(net "SEB_PEER_2A_HB")
			(options
				(clearance outline)
				(anchor circle)
			)
			(primitives
				(gr_poly
					(pts
						(arc
							(start -0.1778 -0.2794)
							(mid -0.249642 -0.249642)
							(end -0.2794 -0.1778)
						)
						(arc
							(start -0.2794 0.1778)
							(mid -0.249642 0.249642)
							(end -0.1778 0.2794)
						)
						(arc
							(start 0.1778 0.2794)
							(mid 0.249642 0.249642)
							(end 0.2794 0.1778)
						)
						(arc
							(start 0.2794 -0.1778)
							(mid 0.249642 -0.249642)
							(end 0.1778 -0.2794)
						)
					)
					(width 0)
					(fill yes)
				)
			)
		)
	)
	(footprint ""
		(layer "F.Cu")
		(at 23.614634 -156.80309 -90)
		(property "Reference" "TP16"
			(at 0 0 270)
			(layer "F.SilkS")
			(hide yes)
			(effects
				(font
					(size 1.27 1.27)
				)
			)
		)
		(property "Value" "TPAD32-GP"
			(at 0 -3.166364 270)
			(unlocked yes)
			(layer "F.Fab")
			(hide yes)
			(effects
				(font
					(size 1.016 1.016)
					(thickness 0.1524)
				)
			)
		)
		(property "Device Type" "TPAD32"
			(at 0 -4.690618 270)
			(unlocked yes)
			(layer "F.Fab")
			(hide yes)
			(effects
				(font
					(size 1.016 1.016)
					(thickness 0.1524)
				)
			)
		)
		(duplicate_pad_numbers_are_jumpers no)
		(fp_poly
			(pts
				(arc
					(start 0.7112 0)
					(mid -0.7112 0)
					(end 0.7112 0)
				)
			)
			(stroke
				(width 0)
				(type default)
			)
			(fill no)
			(layer "F.CrtYd")
		)
		(fp_poly
			(pts
				(arc
					(start 0.7112 0)
					(mid -0.7112 0)
					(end 0.7112 0)
				)
			)
			(stroke
				(width 0)
				(type default)
			)
			(fill no)
			(layer "F.Fab")
		)
		(pad "1" smd circle
			(at 0 0 270)
			(size 0.8128 0.8128)
			(layers "F.Cu" "F.Mask" "F.Paste")
			(net "NCT7904_LED")
		)
	)
	(footprint ""
		(layer "F.Cu")
		(at 40.132 -122.428)
		(property "Reference" "PR63"
			(at 0 0 0)
			(layer "F.SilkS")
			(hide yes)
			(effects
				(font
					(size 1.27 1.27)
				)
			)
		)
		(property "Value" "D002R2512F-GP"
			(at -3.228594 -1.194054 0)
			(unlocked yes)
			(layer "F.Fab")
			(hide yes)
			(effects
				(font
					(size 1.016 1.016)
					(thickness 0.1524)
				)
			)
		)
		(property "Device Type" "R2512-2H32"
			(at -3.228594 -2.718054 0)
			(unlocked yes)
			(layer "F.Fab")
			(hide yes)
			(effects
				(font
					(size 1.016 1.016)
					(thickness 0.1524)
				)
			)
		)
		(duplicate_pad_numbers_are_jumpers no)
		(fp_line
			(start -1.9685 -3.81)
			(end 1.9685 -3.81)
			(stroke
				(width 0.1524)
				(type default)
			)
			(layer "F.SilkS")
		)
		(fp_line
			(start -1.9685 3.81)
			(end -1.9685 -3.81)
			(stroke
				(width 0.1524)
				(type default)
			)
			(layer "F.SilkS")
		)
		(fp_line
			(start 1.9685 -3.81)
			(end 1.9685 3.81)
			(stroke
				(width 0.1524)
				(type default)
			)
			(layer "F.SilkS")
		)
		(fp_line
			(start 1.9685 3.81)
			(end -1.9685 3.81)
			(stroke
				(width 0.1524)
				(type default)
			)
			(layer "F.SilkS")
		)
		(fp_rect
			(start -1.5875 3.175)
			(end 1.5875 -3.175)
			(stroke
				(width 0)
				(type default)
			)
			(fill no)
			(layer "F.CrtYd")
		)
		(fp_poly
			(pts
				(xy -2.2225 3.8862) (xy -2.2225 0.00254) (xy -1.5875 0.00254) (xy -1.5875 3.175) (xy 1.5875 3.175)
				(xy 1.5875 -3.175) (xy -1.5875 -3.175) (xy -1.5875 -0.00254) (xy -2.2225 -0.00254) (xy -2.2225 -3.8862)
				(xy 2.2225 -3.8862) (xy 2.2225 3.8862)
			)
			(stroke
				(width 0)
				(type default)
			)
			(fill no)
			(layer "F.CrtYd")
		)
		(fp_rect
			(start -2.2225 3.8862)
			(end 2.2225 -3.8862)
			(stroke
				(width 0)
				(type default)
			)
			(fill no)
			(layer "F.Fab")
		)
		(pad "1" smd rect
			(at 0 -2.273808)
			(size 3.429 2.5654)
			(layers "F.Cu" "F.Mask" "F.Paste")
			(net "P12V")
		)
		(pad "2" smd rect
			(at 0 2.273808)
			(size 3.429 2.5654)
			(layers "F.Cu" "F.Mask" "F.Paste")
			(net "P12VL_NET")
		)
	)
	(footprint ""
		(layer "F.Cu")
		(at 23.4442 -222.416116 180)
		(property "Reference" "C15"
			(at 0 0 180)
			(layer "F.SilkS")
			(hide yes)
			(effects
				(font
					(size 1.27 1.27)
				)
			)
		)
		(property "Value" "SC1U16V3KX-5GP"
			(at 0 -2.8194 180)
			(unlocked yes)
			(layer "F.Fab")
			(hide yes)
			(effects
				(font
					(size 1.016 1.016)
					(thickness 0.1524)
				)
			)
		)
		(property "Device Type" "C603H36"
			(at 0 -4.3434 180)
			(unlocked yes)
			(layer "F.Fab")
			(hide yes)
			(effects
				(font
					(size 1.016 1.016)
					(thickness 0.1524)
				)
			)
		)
		(duplicate_pad_numbers_are_jumpers no)
		(fp_line
			(start 0.508 0)
			(end -0.508 0)
			(stroke
				(width 0.2032)
				(type default)
			)
			(layer "F.SilkS")
		)
		(fp_rect
			(start -0.5842 1.3335)
			(end 0.5842 -1.3335)
			(stroke
				(width 0)
				(type default)
			)
			(fill no)
			(layer "F.CrtYd")
		)
		(fp_rect
			(start -0.5842 1.3335)
			(end 0.5842 -1.3335)
			(stroke
				(width 0)
				(type default)
			)
			(fill no)
			(layer "F.Fab")
		)
		(pad "1" smd custom
			(at 0 -0.762 180)
			(size 0.2159 0.2159)
			(layers "F.Cu" "F.Mask" "F.Paste")
			(net "P3V3")
			(options
				(clearance outline)
				(anchor circle)
			)
			(primitives
				(gr_poly
					(pts
						(arc
							(start -0.3302 -0.4318)
							(mid -0.402042 -0.402042)
							(end -0.4318 -0.3302)
						)
						(arc
							(start -0.4318 0.3302)
							(mid -0.402042 0.402042)
							(end -0.3302 0.4318)
						)
						(arc
							(start 0.3302 0.4318)
							(mid 0.402042 0.402042)
							(end 0.4318 0.3302)
						)
						(arc
							(start 0.4318 -0.3302)
							(mid 0.402042 -0.402042)
							(end 0.3302 -0.4318)
						)
					)
					(width 0)
					(fill yes)
				)
			)
		)
		(pad "2" smd custom
			(at 0 0.762 180)
			(size 0.2159 0.2159)
			(layers "F.Cu" "F.Mask" "F.Paste")
			(net "GND")
			(options
				(clearance outline)
				(anchor circle)
			)
			(primitives
				(gr_poly
					(pts
						(arc
							(start -0.3302 -0.4318)
							(mid -0.402042 -0.402042)
							(end -0.4318 -0.3302)
						)
						(arc
							(start -0.4318 0.3302)
							(mid -0.402042 0.402042)
							(end -0.3302 0.4318)
						)
						(arc
							(start 0.3302 0.4318)
							(mid 0.402042 0.402042)
							(end 0.4318 0.3302)
						)
						(arc
							(start 0.4318 -0.3302)
							(mid 0.402042 -0.402042)
							(end 0.3302 -0.4318)
						)
					)
					(width 0)
					(fill yes)
				)
			)
		)
	)
	(footprint ""
		(layer "F.Cu")
		(at 11.4554 -147.3454)
		(property "Reference" "R70"
			(at 0 0 0)
			(layer "F.SilkS")
			(hide yes)
			(effects
				(font
					(size 1.27 1.27)
				)
			)
		)
		(property "Value" "27KR3F-GP"
			(at -0.0254 -2.5146 0)
			(unlocked yes)
			(layer "F.Fab")
			(hide yes)
			(effects
				(font
					(size 1.016 1.016)
					(thickness 0.1524)
				)
			)
		)
		(property "Device Type" "R603H22"
			(at -0.0254 -4.0386 0)
			(unlocked yes)
			(layer "F.Fab")
			(hide yes)
			(effects
				(font
					(size 1.016 1.016)
					(thickness 0.1524)
				)
			)
		)
		(duplicate_pad_numbers_are_jumpers no)
		(fp_line
			(start -0.4826 0)
			(end -0.2032 0)
			(stroke
				(width 0.2032)
				(type default)
			)
			(layer "F.SilkS")
		)
		(fp_line
			(start 0.2032 0)
			(end 0.4826 0)
			(stroke
				(width 0.2032)
				(type default)
			)
			(layer "F.SilkS")
		)
		(fp_rect
			(start -0.5842 1.3335)
			(end 0.5842 -1.3335)
			(stroke
				(width 0)
				(type default)
			)
			(fill no)
			(layer "F.CrtYd")
		)
		(fp_rect
			(start -0.5842 1.3335)
			(end 0.5842 -1.3335)
			(stroke
				(width 0)
				(type default)
			)
			(fill no)
			(layer "F.Fab")
		)
		(pad "1" smd custom
			(at 0 -0.762)
			(size 0.2159 0.2159)
			(layers "F.Cu" "F.Mask" "F.Paste")
			(net "FAN_TACH10")
			(options
				(clearance outline)
				(anchor circle)
			)
			(primitives
				(gr_poly
					(pts
						(arc
							(start -0.3302 -0.4318)
							(mid -0.402042 -0.402042)
							(end -0.4318 -0.3302)
						)
						(arc
							(start -0.4318 0.3302)
							(mid -0.402042 0.402042)
							(end -0.3302 0.4318)
						)
						(arc
							(start 0.3302 0.4318)
							(mid 0.402042 0.402042)
							(end 0.4318 0.3302)
						)
						(arc
							(start 0.4318 -0.3302)
							(mid 0.402042 -0.402042)
							(end 0.3302 -0.4318)
						)
					)
					(width 0)
					(fill yes)
				)
			)
		)
		(pad "2" smd custom
			(at 0 0.762)
			(size 0.2159 0.2159)
			(layers "F.Cu" "F.Mask" "F.Paste")
			(net "FANIN_10")
			(options
				(clearance outline)
				(anchor circle)
			)
			(primitives
				(gr_poly
					(pts
						(arc
							(start -0.3302 -0.4318)
							(mid -0.402042 -0.402042)
							(end -0.4318 -0.3302)
						)
						(arc
							(start -0.4318 0.3302)
							(mid -0.402042 0.402042)
							(end -0.3302 0.4318)
						)
						(arc
							(start 0.3302 0.4318)
							(mid 0.402042 0.402042)
							(end 0.4318 0.3302)
						)
						(arc
							(start 0.4318 -0.3302)
							(mid 0.402042 -0.402042)
							(end 0.3302 -0.4318)
						)
					)
					(width 0)
					(fill yes)
				)
			)
		)
	)
	(footprint ""
		(layer "F.Cu")
		(at 23.622 -368.554 90)
		(property "Reference" "PR35"
			(at 0 0 90)
			(layer "F.SilkS")
			(hide yes)
			(effects
				(font
					(size 1.27 1.27)
				)
			)
		)
		(property "Value" "4K7R2J-2-GP"
			(at 0.064008 -3.993896 90)
			(unlocked yes)
			(layer "F.Fab")
			(hide yes)
			(effects
				(font
					(size 1.016 1.016)
					(thickness 0.1524)
				)
			)
		)
		(property "Device Type" "R402H16"
			(at 0.064008 -5.517896 90)
			(unlocked yes)
			(layer "F.Fab")
			(hide yes)
			(effects
				(font
					(size 1.016 1.016)
					(thickness 0.1524)
				)
			)
		)
		(duplicate_pad_numbers_are_jumpers no)
		(fp_line
			(start 0.508 -0.9398)
			(end -0.508 -0.9398)
			(stroke
				(width 0.1524)
				(type default)
			)
			(layer "F.SilkS")
		)
		(fp_line
			(start -0.508 -0.9398)
			(end -0.508 0.9398)
			(stroke
				(width 0.1524)
				(type default)
			)
			(layer "F.SilkS")
		)
		(fp_rect
			(start -0.508 0.9398)
			(end 0.508 -0.9398)
			(stroke
				(width 0)
				(type default)
			)
			(fill no)
			(layer "F.CrtYd")
		)
		(fp_rect
			(start -0.508 0.9398)
			(end 0.508 -0.9398)
			(stroke
				(width 0)
				(type default)
			)
			(fill no)
			(layer "F.Fab")
		)
		(pad "1" smd custom
			(at 0 -0.4445 90)
			(size 0.1397 0.1397)
			(layers "F.Cu" "F.Mask" "F.Paste")
			(net "ADM1276_UV")
			(options
				(clearance outline)
				(anchor circle)
			)
			(primitives
				(gr_poly
					(pts
						(arc
							(start -0.1778 -0.2794)
							(mid -0.249642 -0.249642)
							(end -0.2794 -0.1778)
						)
						(arc
							(start -0.2794 0.1778)
							(mid -0.249642 0.249642)
							(end -0.1778 0.2794)
						)
						(arc
							(start 0.1778 0.2794)
							(mid 0.249642 0.249642)
							(end 0.2794 0.1778)
						)
						(arc
							(start 0.2794 -0.1778)
							(mid 0.249642 -0.249642)
							(end 0.1778 -0.2794)
						)
					)
					(width 0)
					(fill yes)
				)
			)
		)
		(pad "2" smd custom
			(at 0 0.4445 90)
			(size 0.1397 0.1397)
			(layers "F.Cu" "F.Mask" "F.Paste")
			(net "ADM1276_VCAP")
			(options
				(clearance outline)
				(anchor circle)
			)
			(primitives
				(gr_poly
					(pts
						(arc
							(start -0.1778 -0.2794)
							(mid -0.249642 -0.249642)
							(end -0.2794 -0.1778)
						)
						(arc
							(start -0.2794 0.1778)
							(mid -0.249642 0.249642)
							(end -0.1778 0.2794)
						)
						(arc
							(start 0.1778 0.2794)
							(mid 0.249642 0.249642)
							(end 0.2794 0.1778)
						)
						(arc
							(start 0.2794 -0.1778)
							(mid 0.249642 -0.249642)
							(end 0.1778 -0.2794)
						)
					)
					(width 0)
					(fill yes)
				)
			)
		)
	)
	(footprint ""
		(layer "F.Cu")
		(at 18.3388 -179.8828 180)
		(property "Reference" "C55"
			(at 0 0 180)
			(layer "F.SilkS")
			(hide yes)
			(effects
				(font
					(size 1.27 1.27)
				)
			)
		)
		(property "Value" "SC1U16V3KX-5GP"
			(at 0 -2.8194 180)
			(unlocked yes)
			(layer "F.Fab")
			(hide yes)
			(effects
				(font
					(size 1.016 1.016)
					(thickness 0.1524)
				)
			)
		)
		(property "Device Type" "C603H36"
			(at 0 -4.3434 180)
			(unlocked yes)
			(layer "F.Fab")
			(hide yes)
			(effects
				(font
					(size 1.016 1.016)
					(thickness 0.1524)
				)
			)
		)
		(duplicate_pad_numbers_are_jumpers no)
		(fp_line
			(start 0.508 0)
			(end -0.508 0)
			(stroke
				(width 0.2032)
				(type default)
			)
			(layer "F.SilkS")
		)
		(fp_rect
			(start -0.5842 1.3335)
			(end 0.5842 -1.3335)
			(stroke
				(width 0)
				(type default)
			)
			(fill no)
			(layer "F.CrtYd")
		)
		(fp_rect
			(start -0.5842 1.3335)
			(end 0.5842 -1.3335)
			(stroke
				(width 0)
				(type default)
			)
			(fill no)
			(layer "F.Fab")
		)
		(pad "1" smd custom
			(at 0 -0.762 180)
			(size 0.2159 0.2159)
			(layers "F.Cu" "F.Mask" "F.Paste")
			(net "P3V3")
			(options
				(clearance outline)
				(anchor circle)
			)
			(primitives
				(gr_poly
					(pts
						(arc
							(start -0.3302 -0.4318)
							(mid -0.402042 -0.402042)
							(end -0.4318 -0.3302)
						)
						(arc
							(start -0.4318 0.3302)
							(mid -0.402042 0.402042)
							(end -0.3302 0.4318)
						)
						(arc
							(start 0.3302 0.4318)
							(mid 0.402042 0.402042)
							(end 0.4318 0.3302)
						)
						(arc
							(start 0.4318 -0.3302)
							(mid 0.402042 -0.402042)
							(end 0.3302 -0.4318)
						)
					)
					(width 0)
					(fill yes)
				)
			)
		)
		(pad "2" smd custom
			(at 0 0.762 180)
			(size 0.2159 0.2159)
			(layers "F.Cu" "F.Mask" "F.Paste")
			(net "GND")
			(options
				(clearance outline)
				(anchor circle)
			)
			(primitives
				(gr_poly
					(pts
						(arc
							(start -0.3302 -0.4318)
							(mid -0.402042 -0.402042)
							(end -0.4318 -0.3302)
						)
						(arc
							(start -0.4318 0.3302)
							(mid -0.402042 0.402042)
							(end -0.3302 0.4318)
						)
						(arc
							(start 0.3302 0.4318)
							(mid 0.402042 0.402042)
							(end 0.4318 0.3302)
						)
						(arc
							(start 0.4318 -0.3302)
							(mid 0.402042 -0.402042)
							(end 0.3302 -0.4318)
						)
					)
					(width 0)
					(fill yes)
				)
			)
		)
	)
)
